(kicad_pcb
	(version 20260206)
	(generator "pcbnew")
	(generator_version "10.0")
	(general
		(thickness 1.6)
		(legacy_teardrops no)
	)
	(paper "A4")
	(title_block
		(title "03242023_DA0F0TMBIJ0_F0T_Motherboard_J_brd_V01_OCP.brd")
		(comment 1 "Grand Teton / footprints 3851-3856 of 6105")
	)
	(layers
		(0 "F.Cu" signal "TOP")
		(4 "In1.Cu" signal "GND")
		(6 "In2.Cu" signal "IN1")
		(8 "In3.Cu" signal "GND1")
		(10 "In4.Cu" signal "IN2")
		(12 "In5.Cu" signal "GND2")
		(14 "In6.Cu" signal "IN3")
		(16 "In7.Cu" signal "GND3")
		(18 "In8.Cu" signal "VCC")
		(20 "In9.Cu" signal "VCC1")
		(22 "In10.Cu" signal "GND4")
		(24 "In11.Cu" signal "IN4")
		(26 "In12.Cu" signal "GND5")
		(28 "In13.Cu" signal "IN5")
		(30 "In14.Cu" signal "GND6")
		(32 "In15.Cu" signal "IN6")
		(34 "In16.Cu" signal "GND7")
		(2 "B.Cu" signal "BOTTOM")
		(9 "F.Adhes" user "F.Adhesive")
		(11 "B.Adhes" user "B.Adhesive")
		(13 "F.Paste" user "Package Geometry/Pastemask Top")
		(15 "B.Paste" user "Package Geometry/Pastemask Bottom")
		(5 "F.SilkS" user "Ref Des/Silkscreen Top")
		(7 "B.SilkS" user "Ref Des/Silkscreen Bottom")
		(1 "F.Mask" user "Board Geometry/Soldermask Top")
		(3 "B.Mask" user "Board Geometry/Soldermask Bottom")
		(17 "Dwgs.User" user "User.Drawings")
		(19 "Cmts.User" user "User.Comments")
		(21 "Eco1.User" user "User.Eco1")
		(23 "Eco2.User" user "User.Eco2")
		(25 "Edge.Cuts" user "Board Geometry/Outline")
		(27 "Margin" user)
		(31 "F.CrtYd" user "Package Geometry/Place Bound Top")
		(29 "B.CrtYd" user "Package Geometry/Place Bound Bottom")
		(35 "F.Fab" user "Ref Des/Assembly Top")
		(33 "B.Fab" user "Ref Des/Assembly Bottom")
	)
	(footprint ""
		(layer "F.Cu")
		(at 123.296426 -315.66739 90)
		(property "Reference" "PC83"
			(at 0 0 90)
			(layer "F.SilkS")
			(hide yes)
			(effects
				(font
					(size 1.27 1.27)
				)
			)
		)
		(property "Value" ""
			(at 0 0 90)
			(layer "F.Fab")
			(effects
				(font
					(size 1.27 1.27)
				)
			)
		)
		(duplicate_pad_numbers_are_jumpers no)
		(fp_line
			(start 2.750058 0.999998)
			(end -2.750058 0.999998)
			(stroke
				(width 0.1524)
				(type default)
			)
			(layer "F.SilkS")
		)
		(fp_circle
			(center 0 0.999998)
			(end 0 3.750056)
			(stroke
				(width 0.1524)
				(type default)
			)
			(fill no)
			(layer "F.SilkS")
		)
		(fp_poly
			(pts
				(arc
					(start 2.750058 0.999998)
					(mid 0 3.750056)
					(end -2.750058 0.999998)
				)
			)
			(stroke
				(width 0)
				(type default)
			)
			(fill yes)
			(layer "F.SilkS")
		)
		(fp_circle
			(center 0 0.999998)
			(end 0 3.750056)
			(stroke
				(width 0.1)
				(type default)
			)
			(fill no)
			(layer "F.Fab")
		)
		(pad "1" thru_hole rect
			(at 0 0 90)
			(size 1.5748 1.5748)
			(drill 1.0668)
			(layers "*.Cu" "*.Mask")
			(remove_unused_layers no)
			(net "PVCCIN_CPU1")
			(clearance 0)
			(padstack
				(mode front_inner_back)
				(layer "Inner"
					(shape circle)
					(size 1.5748 1.5748)
					(clearance 0)
				)
				(layer "B.Cu"
					(shape rect)
					(size 1.5748 1.5748)
					(clearance 0)
				)
			)
		)
		(pad "2" thru_hole circle
			(at 0 1.999996 90)
			(size 1.5748 1.5748)
			(drill 1.0668)
			(layers "*.Cu" "*.Mask")
			(remove_unused_layers no)
			(net "GND")
			(clearance 0)
		)
	)
	(footprint ""
		(layer "F.Cu")
		(at 208.1022 -114.0968 180)
		(property "Reference" "C2380"
			(at 0 0 180)
			(layer "F.SilkS")
			(hide yes)
			(effects
				(font
					(size 1.27 1.27)
				)
			)
		)
		(property "Value" ""
			(at 0 0 180)
			(layer "F.Fab")
			(effects
				(font
					(size 1.27 1.27)
				)
			)
		)
		(duplicate_pad_numbers_are_jumpers no)
		(fp_line
			(start 0.7874 0.4064)
			(end -0.7874 0.4064)
			(stroke
				(width 0.1524)
				(type default)
			)
			(layer "F.SilkS")
		)
		(fp_line
			(start 0.7874 -0.4064)
			(end 0.7874 0.4064)
			(stroke
				(width 0.1524)
				(type default)
			)
			(layer "F.SilkS")
		)
		(fp_line
			(start -0.7874 0.4064)
			(end -0.7874 -0.4064)
			(stroke
				(width 0.1524)
				(type default)
			)
			(layer "F.SilkS")
		)
		(fp_line
			(start -0.7874 -0.4064)
			(end 0.7874 -0.4064)
			(stroke
				(width 0.1524)
				(type default)
			)
			(layer "F.SilkS")
		)
		(fp_line
			(start 0.67945 0.3048)
			(end 0.120396 0.3048)
			(stroke
				(width 0.1)
				(type default)
			)
			(layer "F.Fab")
		)
		(fp_line
			(start 0.67945 -0.3048)
			(end 0.67945 0.3048)
			(stroke
				(width 0.1)
				(type default)
			)
			(layer "F.Fab")
		)
		(fp_line
			(start 0.12065 -0.2794)
			(end 0.12065 -0.3048)
			(stroke
				(width 0.1)
				(type default)
			)
			(layer "F.Fab")
		)
		(fp_line
			(start 0.12065 -0.3048)
			(end 0.67945 -0.3048)
			(stroke
				(width 0.1)
				(type default)
			)
			(layer "F.Fab")
		)
		(fp_line
			(start 0.120396 0.3048)
			(end 0.120396 0.2794)
			(stroke
				(width 0.1)
				(type default)
			)
			(layer "F.Fab")
		)
		(fp_line
			(start 0.120396 0.2794)
			(end -0.12065 0.2794)
			(stroke
				(width 0.1)
				(type default)
			)
			(layer "F.Fab")
		)
		(fp_line
			(start -0.12065 0.3048)
			(end -0.67945 0.3048)
			(stroke
				(width 0.1)
				(type default)
			)
			(layer "F.Fab")
		)
		(fp_line
			(start -0.12065 0.2794)
			(end -0.12065 0.3048)
			(stroke
				(width 0.1)
				(type default)
			)
			(layer "F.Fab")
		)
		(fp_line
			(start -0.12065 -0.2794)
			(end 0.12065 -0.2794)
			(stroke
				(width 0.1)
				(type default)
			)
			(layer "F.Fab")
		)
		(fp_line
			(start -0.12065 -0.305054)
			(end -0.12065 -0.2794)
			(stroke
				(width 0.1)
				(type default)
			)
			(layer "F.Fab")
		)
		(fp_line
			(start -0.67945 0.3048)
			(end -0.67945 -0.305054)
			(stroke
				(width 0.1)
				(type default)
			)
			(layer "F.Fab")
		)
		(fp_line
			(start -0.67945 -0.305054)
			(end -0.12065 -0.305054)
			(stroke
				(width 0.1)
				(type default)
			)
			(layer "F.Fab")
		)
		(pad "1" smd circle
			(at -0.40005 0 180)
			(size 0 0)
			(layers "F.Cu" "F.Mask" "F.Paste")
			(net "UV_P2V5_COMP")
		)
		(pad "2" smd circle
			(at 0.40005 0 180)
			(size 0 0)
			(layers "F.Cu" "F.Mask" "F.Paste")
			(net "GND")
		)
	)
	(footprint ""
		(layer "F.Cu")
		(at 350.78543 -355.773736)
		(property "Reference" "R2370"
			(at 0 0 0)
			(layer "F.SilkS")
			(hide yes)
			(effects
				(font
					(size 1.27 1.27)
				)
			)
		)
		(property "Value" ""
			(at 0 0 0)
			(layer "F.Fab")
			(effects
				(font
					(size 1.27 1.27)
				)
			)
		)
		(duplicate_pad_numbers_are_jumpers no)
		(fp_line
			(start -0.7874 -0.4064)
			(end 0.7874 -0.4064)
			(stroke
				(width 0.1524)
				(type default)
			)
			(layer "F.SilkS")
		)
		(fp_line
			(start -0.7874 0.4064)
			(end -0.7874 -0.4064)
			(stroke
				(width 0.1524)
				(type default)
			)
			(layer "F.SilkS")
		)
		(fp_line
			(start 0.7874 -0.4064)
			(end 0.7874 0.4064)
			(stroke
				(width 0.1524)
				(type default)
			)
			(layer "F.SilkS")
		)
		(fp_line
			(start 0.7874 0.4064)
			(end -0.7874 0.4064)
			(stroke
				(width 0.1524)
				(type default)
			)
			(layer "F.SilkS")
		)
		(fp_line
			(start -0.67945 -0.305054)
			(end -0.12065 -0.305054)
			(stroke
				(width 0.1)
				(type default)
			)
			(layer "F.Fab")
		)
		(fp_line
			(start -0.67945 0.3048)
			(end -0.67945 -0.305054)
			(stroke
				(width 0.1)
				(type default)
			)
			(layer "F.Fab")
		)
		(fp_line
			(start -0.12065 -0.305054)
			(end -0.12065 -0.2794)
			(stroke
				(width 0.1)
				(type default)
			)
			(layer "F.Fab")
		)
		(fp_line
			(start -0.12065 -0.2794)
			(end 0.12065 -0.2794)
			(stroke
				(width 0.1)
				(type default)
			)
			(layer "F.Fab")
		)
		(fp_line
			(start -0.12065 0.2794)
			(end -0.12065 0.3048)
			(stroke
				(width 0.1)
				(type default)
			)
			(layer "F.Fab")
		)
		(fp_line
			(start -0.12065 0.3048)
			(end -0.67945 0.3048)
			(stroke
				(width 0.1)
				(type default)
			)
			(layer "F.Fab")
		)
		(fp_line
			(start 0.120396 0.2794)
			(end -0.12065 0.2794)
			(stroke
				(width 0.1)
				(type default)
			)
			(layer "F.Fab")
		)
		(fp_line
			(start 0.120396 0.3048)
			(end 0.120396 0.2794)
			(stroke
				(width 0.1)
				(type default)
			)
			(layer "F.Fab")
		)
		(fp_line
			(start 0.12065 -0.3048)
			(end 0.67945 -0.3048)
			(stroke
				(width 0.1)
				(type default)
			)
			(layer "F.Fab")
		)
		(fp_line
			(start 0.12065 -0.2794)
			(end 0.12065 -0.3048)
			(stroke
				(width 0.1)
				(type default)
			)
			(layer "F.Fab")
		)
		(fp_line
			(start 0.67945 -0.3048)
			(end 0.67945 0.3048)
			(stroke
				(width 0.1)
				(type default)
			)
			(layer "F.Fab")
		)
		(fp_line
			(start 0.67945 0.3048)
			(end 0.120396 0.3048)
			(stroke
				(width 0.1)
				(type default)
			)
			(layer "F.Fab")
		)
		(pad "1" smd circle
			(at -0.40005 0)
			(size 0 0)
			(layers "F.Cu" "F.Mask" "F.Paste")
			(net "SVID_ALERT0_CPU0_R_N")
		)
		(pad "2" smd circle
			(at 0.40005 0)
			(size 0 0)
			(layers "F.Cu" "F.Mask" "F.Paste")
			(net "SVID_ALERT_PVCCIN_CPU0_R")
		)
	)
	(footprint ""
		(layer "F.Cu")
		(at 210.560158 -104.96804)
		(property "Reference" "R4804"
			(at 0 0 0)
			(layer "F.SilkS")
			(hide yes)
			(effects
				(font
					(size 1.27 1.27)
				)
			)
		)
		(property "Value" ""
			(at 0 0 0)
			(layer "F.Fab")
			(effects
				(font
					(size 1.27 1.27)
				)
			)
		)
		(duplicate_pad_numbers_are_jumpers no)
		(fp_line
			(start -0.7874 -0.4064)
			(end 0.7874 -0.4064)
			(stroke
				(width 0.1524)
				(type default)
			)
			(layer "F.SilkS")
		)
		(fp_line
			(start -0.7874 0.4064)
			(end -0.7874 -0.4064)
			(stroke
				(width 0.1524)
				(type default)
			)
			(layer "F.SilkS")
		)
		(fp_line
			(start 0.7874 -0.4064)
			(end 0.7874 0.4064)
			(stroke
				(width 0.1524)
				(type default)
			)
			(layer "F.SilkS")
		)
		(fp_line
			(start 0.7874 0.4064)
			(end -0.7874 0.4064)
			(stroke
				(width 0.1524)
				(type default)
			)
			(layer "F.SilkS")
		)
		(fp_line
			(start -0.67945 -0.305054)
			(end -0.12065 -0.305054)
			(stroke
				(width 0.1)
				(type default)
			)
			(layer "F.Fab")
		)
		(fp_line
			(start -0.67945 0.3048)
			(end -0.67945 -0.305054)
			(stroke
				(width 0.1)
				(type default)
			)
			(layer "F.Fab")
		)
		(fp_line
			(start -0.12065 -0.305054)
			(end -0.12065 -0.2794)
			(stroke
				(width 0.1)
				(type default)
			)
			(layer "F.Fab")
		)
		(fp_line
			(start -0.12065 -0.2794)
			(end 0.12065 -0.2794)
			(stroke
				(width 0.1)
				(type default)
			)
			(layer "F.Fab")
		)
		(fp_line
			(start -0.12065 0.2794)
			(end -0.12065 0.3048)
			(stroke
				(width 0.1)
				(type default)
			)
			(layer "F.Fab")
		)
		(fp_line
			(start -0.12065 0.3048)
			(end -0.67945 0.3048)
			(stroke
				(width 0.1)
				(type default)
			)
			(layer "F.Fab")
		)
		(fp_line
			(start 0.120396 0.2794)
			(end -0.12065 0.2794)
			(stroke
				(width 0.1)
				(type default)
			)
			(layer "F.Fab")
		)
		(fp_line
			(start 0.120396 0.3048)
			(end 0.120396 0.2794)
			(stroke
				(width 0.1)
				(type default)
			)
			(layer "F.Fab")
		)
		(fp_line
			(start 0.12065 -0.3048)
			(end 0.67945 -0.3048)
			(stroke
				(width 0.1)
				(type default)
			)
			(layer "F.Fab")
		)
		(fp_line
			(start 0.12065 -0.2794)
			(end 0.12065 -0.3048)
			(stroke
				(width 0.1)
				(type default)
			)
			(layer "F.Fab")
		)
		(fp_line
			(start 0.67945 -0.3048)
			(end 0.67945 0.3048)
			(stroke
				(width 0.1)
				(type default)
			)
			(layer "F.Fab")
		)
		(fp_line
			(start 0.67945 0.3048)
			(end 0.120396 0.3048)
			(stroke
				(width 0.1)
				(type default)
			)
			(layer "F.Fab")
		)
		(pad "1" smd circle
			(at -0.40005 0)
			(size 0 0)
			(layers "F.Cu" "F.Mask" "F.Paste")
			(net "P3V3_AUX")
		)
		(pad "2" smd circle
			(at 0.40005 0)
			(size 0 0)
			(layers "F.Cu" "F.Mask" "F.Paste")
			(net "U205_VDD")
		)
	)
	(footprint ""
		(layer "F.Cu")
		(at 443.23 -74.640948 90)
		(property "Reference" "PC591"
			(at 0 0 90)
			(layer "F.SilkS")
			(hide yes)
			(effects
				(font
					(size 1.27 1.27)
				)
			)
		)
		(property "Value" ""
			(at 0 0 90)
			(layer "F.Fab")
			(effects
				(font
					(size 1.27 1.27)
				)
			)
		)
		(duplicate_pad_numbers_are_jumpers no)
		(fp_line
			(start 1.2954 -0.5842)
			(end 1.2954 0.5842)
			(stroke
				(width 0.1524)
				(type default)
			)
			(layer "F.SilkS")
		)
		(fp_line
			(start 0 -0.5842)
			(end 0 0.5842)
			(stroke
				(width 0.1524)
				(type default)
			)
			(layer "F.SilkS")
		)
		(fp_line
			(start -1.2954 -0.5842)
			(end 1.2954 -0.5842)
			(stroke
				(width 0.1524)
				(type default)
			)
			(layer "F.SilkS")
		)
		(fp_line
			(start 1.2954 0.5842)
			(end -1.2954 0.5842)
			(stroke
				(width 0.1524)
				(type default)
			)
			(layer "F.SilkS")
		)
		(fp_line
			(start -1.2954 0.5842)
			(end -1.2954 -0.5842)
			(stroke
				(width 0.1524)
				(type default)
			)
			(layer "F.SilkS")
		)
		(fp_line
			(start 0.8636 -0.4572)
			(end 0.8636 -0.4064)
			(stroke
				(width 0.1)
				(type default)
			)
			(layer "F.Fab")
		)
		(fp_line
			(start -0.8636 -0.4572)
			(end 0.8636 -0.4572)
			(stroke
				(width 0.1)
				(type default)
			)
			(layer "F.Fab")
		)
		(fp_line
			(start 1.1938 -0.4064)
			(end 1.1938 0.4064)
			(stroke
				(width 0.1)
				(type default)
			)
			(layer "F.Fab")
		)
		(fp_line
			(start 0.8636 -0.4064)
			(end 1.1938 -0.4064)
			(stroke
				(width 0.1)
				(type default)
			)
			(layer "F.Fab")
		)
		(fp_line
			(start -0.8636 -0.4064)
			(end -0.8636 -0.4572)
			(stroke
				(width 0.1)
				(type default)
			)
			(layer "F.Fab")
		)
		(fp_line
			(start -1.1938 -0.4064)
			(end -0.8636 -0.4064)
			(stroke
				(width 0.1)
				(type default)
			)
			(layer "F.Fab")
		)
		(fp_line
			(start 1.1938 0.4064)
			(end 0.8636 0.4064)
			(stroke
				(width 0.1)
				(type default)
			)
			(layer "F.Fab")
		)
		(fp_line
			(start 0.8636 0.4064)
			(end 0.8636 0.4572)
			(stroke
				(width 0.1)
				(type default)
			)
			(layer "F.Fab")
		)
		(fp_line
			(start -0.8636 0.4064)
			(end -1.1938 0.4064)
			(stroke
				(width 0.1)
				(type default)
			)
			(layer "F.Fab")
		)
		(fp_line
			(start -1.1938 0.4064)
			(end -1.1938 -0.4064)
			(stroke
				(width 0.1)
				(type default)
			)
			(layer "F.Fab")
		)
		(fp_line
			(start 0.8636 0.4572)
			(end -0.8636 0.4572)
			(stroke
				(width 0.1)
				(type default)
			)
			(layer "F.Fab")
		)
		(fp_line
			(start -0.8636 0.4572)
			(end -0.8636 0.4064)
			(stroke
				(width 0.1)
				(type default)
			)
			(layer "F.Fab")
		)
		(pad "1" smd rect
			(at -0.7366 0)
			(size 0.7112 0.8128)
			(layers "F.Cu" "F.Mask" "F.Paste")
			(net "P3V3_AUX_VCC")
		)
		(pad "2" smd rect
			(at 0.7366 0)
			(size 0.7112 0.8128)
			(layers "F.Cu" "F.Mask" "F.Paste")
			(net "GND")
		)
	)
	(footprint ""
		(layer "F.Cu")
		(at 85.915246 -57.279286 90)
		(property "Reference" "PC190"
			(at 0 0 90)
			(layer "F.SilkS")
			(hide yes)
			(effects
				(font
					(size 1.27 1.27)
				)
			)
		)
		(property "Value" ""
			(at 0 0 90)
			(layer "F.Fab")
			(effects
				(font
					(size 1.27 1.27)
				)
			)
		)
		(duplicate_pad_numbers_are_jumpers no)
		(fp_line
			(start 0.7874 -0.4064)
			(end 0.7874 0.4064)
			(stroke
				(width 0.1524)
				(type default)
			)
			(layer "F.SilkS")
		)
		(fp_line
			(start -0.7874 -0.4064)
			(end 0.7874 -0.4064)
			(stroke
				(width 0.1524)
				(type default)
			)
			(layer "F.SilkS")
		)
		(fp_line
			(start 0.7874 0.4064)
			(end -0.7874 0.4064)
			(stroke
				(width 0.1524)
				(type default)
			)
			(layer "F.SilkS")
		)
		(fp_line
			(start -0.7874 0.4064)
			(end -0.7874 -0.4064)
			(stroke
				(width 0.1524)
				(type default)
			)
			(layer "F.SilkS")
		)
		(fp_line
			(start -0.12065 -0.305054)
			(end -0.12065 -0.2794)
			(stroke
				(width 0.1)
				(type default)
			)
			(layer "F.Fab")
		)
		(fp_line
			(start -0.67945 -0.305054)
			(end -0.12065 -0.305054)
			(stroke
				(width 0.1)
				(type default)
			)
			(layer "F.Fab")
		)
		(fp_line
			(start 0.67945 -0.3048)
			(end 0.67945 0.3048)
			(stroke
				(width 0.1)
				(type default)
			)
			(layer "F.Fab")
		)
		(fp_line
			(start 0.12065 -0.3048)
			(end 0.67945 -0.3048)
			(stroke
				(width 0.1)
				(type default)
			)
			(layer "F.Fab")
		)
		(fp_line
			(start 0.12065 -0.2794)
			(end 0.12065 -0.3048)
			(stroke
				(width 0.1)
				(type default)
			)
			(layer "F.Fab")
		)
		(fp_line
			(start -0.12065 -0.2794)
			(end 0.12065 -0.2794)
			(stroke
				(width 0.1)
				(type default)
			)
			(layer "F.Fab")
		)
		(fp_line
			(start 0.120396 0.2794)
			(end -0.12065 0.2794)
			(stroke
				(width 0.1)
				(type default)
			)
			(layer "F.Fab")
		)
		(fp_line
			(start -0.12065 0.2794)
			(end -0.12065 0.3048)
			(stroke
				(width 0.1)
				(type default)
			)
			(layer "F.Fab")
		)
		(fp_line
			(start 0.67945 0.3048)
			(end 0.120396 0.3048)
			(stroke
				(width 0.1)
				(type default)
			)
			(layer "F.Fab")
		)
		(fp_line
			(start 0.120396 0.3048)
			(end 0.120396 0.2794)
			(stroke
				(width 0.1)
				(type default)
			)
			(layer "F.Fab")
		)
		(fp_line
			(start -0.12065 0.3048)
			(end -0.67945 0.3048)
			(stroke
				(width 0.1)
				(type default)
			)
			(layer "F.Fab")
		)
		(fp_line
			(start -0.67945 0.3048)
			(end -0.67945 -0.305054)
			(stroke
				(width 0.1)
				(type default)
			)
			(layer "F.Fab")
		)
		(pad "1" smd circle
			(at -0.40005 0 90)
			(size 0 0)
			(layers "F.Cu" "F.Mask" "F.Paste")
			(net "P3V3_OCP_VCC_2")
		)
		(pad "2" smd circle
			(at 0.40005 0 90)
			(size 0 0)
			(layers "F.Cu" "F.Mask" "F.Paste")
			(net "GND")
		)
	)
)
